(kicad_pcb
	(version 20260206)
	(generator "pcbnew")
	(generator_version "10.0")
	(general
		(thickness 1.6)
		(legacy_teardrops no)
	)
	(paper "A4")
	(title_block
		(title "peb — Lightning_PEB_BRD.brd")
		(comment 1 "Lightning (Wiwynn / Facebook NVMe JBOF) / footprints 2279-2287 of 2563")
	)
	(layers
		(0 "F.Cu" signal "TOP")
		(4 "In1.Cu" signal "L2GND")
		(6 "In2.Cu" signal "L3")
		(8 "In3.Cu" signal "L4VCC")
		(10 "In4.Cu" signal "L5VCC")
		(12 "In5.Cu" signal "L6")
		(14 "In6.Cu" signal "L7GND")
		(2 "B.Cu" signal "BOTTOM")
		(9 "F.Adhes" user "F.Adhesive")
		(11 "B.Adhes" user "B.Adhesive")
		(13 "F.Paste" user "Package Geometry/Pastemask Top")
		(15 "B.Paste" user "Package Geometry/Pastemask Bottom")
		(5 "F.SilkS" user "Ref Des/Silkscreen Top")
		(7 "B.SilkS" user "Ref Des/Silkscreen Bottom")
		(1 "F.Mask" user "Board Geometry/Soldermask Top")
		(3 "B.Mask" user "Board Geometry/Soldermask Bottom")
		(17 "Dwgs.User" user "User.Drawings")
		(19 "Cmts.User" user "User.Comments")
		(21 "Eco1.User" user "User.Eco1")
		(23 "Eco2.User" user "User.Eco2")
		(25 "Edge.Cuts" user "Board Geometry/Outline")
		(27 "Margin" user)
		(31 "F.CrtYd" user "Package Geometry/Place Bound Top")
		(29 "B.CrtYd" user "Package Geometry/Place Bound Bottom")
		(35 "F.Fab" user "Ref Des/Assembly Top")
		(33 "B.Fab" user "Ref Des/Assembly Bottom")
	)
	(footprint ""
		(layer "B.Cu")
		(at 243.1288 -51.9938 90)
		(property "Reference" "C444"
			(at 0 0 90)
			(layer "B.SilkS")
			(hide yes)
			(effects
				(font
					(size 1.27 1.27)
				)
				(justify mirror)
			)
		)
		(property "Value" "SCD1U16V1KX-1-GP"
			(at 2.8321 -1.7399 90)
			(unlocked yes)
			(layer "B.Fab")
			(hide yes)
			(effects
				(font
					(size 1.016 1.016)
					(thickness 0.1524)
				)
				(justify mirror)
			)
		)
		(property "Device Type" "C0201H13"
			(at 2.8321 -3.2639 90)
			(unlocked yes)
			(layer "B.Fab")
			(hide yes)
			(effects
				(font
					(size 1.016 1.016)
					(thickness 0.1524)
				)
				(justify mirror)
			)
		)
		(duplicate_pad_numbers_are_jumpers no)
		(fp_rect
			(start 0.2794 0.6477)
			(end -0.2794 -0.6477)
			(stroke
				(width 0)
				(type default)
			)
			(fill no)
			(layer "B.CrtYd")
		)
		(fp_rect
			(start 0.2794 0.6477)
			(end -0.2794 -0.6477)
			(stroke
				(width 0)
				(type default)
			)
			(fill no)
			(layer "B.Fab")
		)
		(pad "1" smd custom
			(at 0 -0.2794 270)
			(size 0.0762 0.0762)
			(layers "B.Cu" "B.Mask" "B.Paste")
			(net "DUT_VDD")
			(options
				(clearance outline)
				(anchor circle)
			)
			(primitives
				(gr_poly
					(pts
						(arc
							(start 0.1524 0.127)
							(mid 0.137521 0.162921)
							(end 0.1016 0.1778)
						)
						(arc
							(start -0.1016 0.1778)
							(mid -0.137521 0.162921)
							(end -0.1524 0.127)
						)
						(arc
							(start -0.1524 -0.127)
							(mid -0.137521 -0.162921)
							(end -0.1016 -0.1778)
						)
						(arc
							(start 0.1016 -0.1778)
							(mid 0.137521 -0.162921)
							(end 0.1524 -0.127)
						)
					)
					(width 0)
					(fill yes)
				)
			)
		)
		(pad "2" smd custom
			(at 0 0.2794 270)
			(size 0.0762 0.0762)
			(layers "B.Cu" "B.Mask" "B.Paste")
			(net "GND")
			(options
				(clearance outline)
				(anchor circle)
			)
			(primitives
				(gr_poly
					(pts
						(arc
							(start 0.1524 0.127)
							(mid 0.137521 0.162921)
							(end 0.1016 0.1778)
						)
						(arc
							(start -0.1016 0.1778)
							(mid -0.137521 0.162921)
							(end -0.1524 0.127)
						)
						(arc
							(start -0.1524 -0.127)
							(mid -0.137521 -0.162921)
							(end -0.1016 -0.1778)
						)
						(arc
							(start 0.1016 -0.1778)
							(mid 0.137521 -0.162921)
							(end 0.1524 -0.127)
						)
					)
					(width 0)
					(fill yes)
				)
			)
		)
	)
	(footprint ""
		(layer "B.Cu")
		(at 233.6038 -40.005)
		(property "Reference" "TP200"
			(at 0 0 0)
			(layer "B.SilkS")
			(hide yes)
			(effects
				(font
					(size 1.27 1.27)
				)
				(justify mirror)
			)
		)
		(property "Value" "TPAD28-2-GP"
			(at 0.0127 -1.6637 0)
			(unlocked yes)
			(layer "B.Fab")
			(hide yes)
			(effects
				(font
					(size 1.016 1.016)
					(thickness 0.1524)
				)
				(justify mirror)
			)
		)
		(property "Device Type" "TPAD28"
			(at 0.0127 -3.1877 0)
			(unlocked yes)
			(layer "B.Fab")
			(hide yes)
			(effects
				(font
					(size 1.016 1.016)
					(thickness 0.1524)
				)
				(justify mirror)
			)
		)
		(duplicate_pad_numbers_are_jumpers no)
		(fp_poly
			(pts
				(arc
					(start 0.3556 0)
					(mid -0.3556 0)
					(end 0.3556 0)
				)
			)
			(stroke
				(width 0)
				(type default)
			)
			(fill no)
			(layer "B.CrtYd")
		)
		(fp_poly
			(pts
				(arc
					(start 0.6096 0)
					(mid -0.6096 0)
					(end 0.6096 0)
				)
			)
			(stroke
				(width 0)
				(type default)
			)
			(fill no)
			(layer "B.Fab")
		)
		(pad "1" smd circle
			(at 0 0 180)
			(size 0.7112 0.7112)
			(layers "B.Cu" "B.Mask" "B.Paste")
			(net "RMII_TX_EN")
		)
	)
	(footprint ""
		(layer "B.Cu")
		(at 61.341 -123.444 -90)
		(property "Reference" "R579"
			(at 0 0 90)
			(layer "B.SilkS")
			(hide yes)
			(effects
				(font
					(size 1.27 1.27)
				)
				(justify mirror)
			)
		)
		(property "Value" "4K7R2F-GP"
			(at -0.064008 -3.993896 270)
			(unlocked yes)
			(layer "B.Fab")
			(hide yes)
			(effects
				(font
					(size 1.016 1.016)
					(thickness 0.1524)
				)
				(justify mirror)
			)
		)
		(property "Device Type" "R402H16"
			(at -0.064008 -5.517896 270)
			(unlocked yes)
			(layer "B.Fab")
			(hide yes)
			(effects
				(font
					(size 1.016 1.016)
					(thickness 0.1524)
				)
				(justify mirror)
			)
		)
		(duplicate_pad_numbers_are_jumpers no)
		(fp_line
			(start -0.508 -0.9398)
			(end 0.508 -0.9398)
			(stroke
				(width 0.1524)
				(type default)
			)
			(layer "B.SilkS")
		)
		(fp_line
			(start 0.508 -0.9398)
			(end 0.508 0.9398)
			(stroke
				(width 0.1524)
				(type default)
			)
			(layer "B.SilkS")
		)
		(fp_rect
			(start 0.508 0.9398)
			(end -0.508 -0.9398)
			(stroke
				(width 0)
				(type default)
			)
			(fill no)
			(layer "B.CrtYd")
		)
		(fp_rect
			(start 0.508 0.9398)
			(end -0.508 -0.9398)
			(stroke
				(width 0)
				(type default)
			)
			(fill no)
			(layer "B.Fab")
		)
		(pad "1" smd custom
			(at 0 -0.4445 90)
			(size 0.1397 0.1397)
			(layers "B.Cu" "B.Mask" "B.Paste")
			(net "BMC_I2C6_C_FCB_SCL")
			(options
				(clearance outline)
				(anchor circle)
			)
			(primitives
				(gr_poly
					(pts
						(arc
							(start -0.1778 0.2794)
							(mid -0.249642 0.249642)
							(end -0.2794 0.1778)
						)
						(arc
							(start -0.2794 -0.1778)
							(mid -0.249642 -0.249642)
							(end -0.1778 -0.2794)
						)
						(arc
							(start 0.1778 -0.2794)
							(mid 0.249642 -0.249642)
							(end 0.2794 -0.1778)
						)
						(arc
							(start 0.2794 0.1778)
							(mid 0.249642 0.249642)
							(end 0.1778 0.2794)
						)
					)
					(width 0)
					(fill yes)
				)
			)
		)
		(pad "2" smd custom
			(at 0 0.4445 90)
			(size 0.1397 0.1397)
			(layers "B.Cu" "B.Mask" "B.Paste")
			(net "P3V3_STBY")
			(options
				(clearance outline)
				(anchor circle)
			)
			(primitives
				(gr_poly
					(pts
						(arc
							(start -0.1778 0.2794)
							(mid -0.249642 0.249642)
							(end -0.2794 0.1778)
						)
						(arc
							(start -0.2794 -0.1778)
							(mid -0.249642 -0.249642)
							(end -0.1778 -0.2794)
						)
						(arc
							(start 0.1778 -0.2794)
							(mid 0.249642 -0.249642)
							(end 0.2794 -0.1778)
						)
						(arc
							(start 0.2794 0.1778)
							(mid 0.249642 0.249642)
							(end 0.1778 0.2794)
						)
					)
					(width 0)
					(fill yes)
				)
			)
		)
	)
	(footprint ""
		(layer "B.Cu")
		(at 243.1288 -54.0004 90)
		(property "Reference" "C440"
			(at 0 0 90)
			(layer "B.SilkS")
			(hide yes)
			(effects
				(font
					(size 1.27 1.27)
				)
				(justify mirror)
			)
		)
		(property "Value" "SCD1U16V1KX-1-GP"
			(at 2.8321 -1.7399 90)
			(unlocked yes)
			(layer "B.Fab")
			(hide yes)
			(effects
				(font
					(size 1.016 1.016)
					(thickness 0.1524)
				)
				(justify mirror)
			)
		)
		(property "Device Type" "C0201H13"
			(at 2.8321 -3.2639 90)
			(unlocked yes)
			(layer "B.Fab")
			(hide yes)
			(effects
				(font
					(size 1.016 1.016)
					(thickness 0.1524)
				)
				(justify mirror)
			)
		)
		(duplicate_pad_numbers_are_jumpers no)
		(fp_rect
			(start 0.2794 0.6477)
			(end -0.2794 -0.6477)
			(stroke
				(width 0)
				(type default)
			)
			(fill no)
			(layer "B.CrtYd")
		)
		(fp_rect
			(start 0.2794 0.6477)
			(end -0.2794 -0.6477)
			(stroke
				(width 0)
				(type default)
			)
			(fill no)
			(layer "B.Fab")
		)
		(pad "1" smd custom
			(at 0 -0.2794 270)
			(size 0.0762 0.0762)
			(layers "B.Cu" "B.Mask" "B.Paste")
			(net "DUT_VDD")
			(options
				(clearance outline)
				(anchor circle)
			)
			(primitives
				(gr_poly
					(pts
						(arc
							(start 0.1524 0.127)
							(mid 0.137521 0.162921)
							(end 0.1016 0.1778)
						)
						(arc
							(start -0.1016 0.1778)
							(mid -0.137521 0.162921)
							(end -0.1524 0.127)
						)
						(arc
							(start -0.1524 -0.127)
							(mid -0.137521 -0.162921)
							(end -0.1016 -0.1778)
						)
						(arc
							(start 0.1016 -0.1778)
							(mid 0.137521 -0.162921)
							(end 0.1524 -0.127)
						)
					)
					(width 0)
					(fill yes)
				)
			)
		)
		(pad "2" smd custom
			(at 0 0.2794 270)
			(size 0.0762 0.0762)
			(layers "B.Cu" "B.Mask" "B.Paste")
			(net "GND")
			(options
				(clearance outline)
				(anchor circle)
			)
			(primitives
				(gr_poly
					(pts
						(arc
							(start 0.1524 0.127)
							(mid 0.137521 0.162921)
							(end 0.1016 0.1778)
						)
						(arc
							(start -0.1016 0.1778)
							(mid -0.137521 0.162921)
							(end -0.1524 0.127)
						)
						(arc
							(start -0.1524 -0.127)
							(mid -0.137521 -0.162921)
							(end -0.1016 -0.1778)
						)
						(arc
							(start 0.1016 -0.1778)
							(mid 0.137521 -0.162921)
							(end 0.1524 -0.127)
						)
					)
					(width 0)
					(fill yes)
				)
			)
		)
	)
	(footprint ""
		(layer "B.Cu")
		(at 238.5822 -35.9918 90)
		(property "Reference" "C466"
			(at 0 0 90)
			(layer "B.SilkS")
			(hide yes)
			(effects
				(font
					(size 1.27 1.27)
				)
				(justify mirror)
			)
		)
		(property "Value" "SCD1U16V1KX-1-GP"
			(at 2.8321 -1.7399 90)
			(unlocked yes)
			(layer "B.Fab")
			(hide yes)
			(effects
				(font
					(size 1.016 1.016)
					(thickness 0.1524)
				)
				(justify mirror)
			)
		)
		(property "Device Type" "C0201H13"
			(at 2.8321 -3.2639 90)
			(unlocked yes)
			(layer "B.Fab")
			(hide yes)
			(effects
				(font
					(size 1.016 1.016)
					(thickness 0.1524)
				)
				(justify mirror)
			)
		)
		(duplicate_pad_numbers_are_jumpers no)
		(fp_rect
			(start 0.2794 0.6477)
			(end -0.2794 -0.6477)
			(stroke
				(width 0)
				(type default)
			)
			(fill no)
			(layer "B.CrtYd")
		)
		(fp_rect
			(start 0.2794 0.6477)
			(end -0.2794 -0.6477)
			(stroke
				(width 0)
				(type default)
			)
			(fill no)
			(layer "B.Fab")
		)
		(pad "1" smd custom
			(at 0 -0.2794 270)
			(size 0.0762 0.0762)
			(layers "B.Cu" "B.Mask" "B.Paste")
			(net "DUT_VDDO_REF")
			(options
				(clearance outline)
				(anchor circle)
			)
			(primitives
				(gr_poly
					(pts
						(arc
							(start 0.1524 0.127)
							(mid 0.137521 0.162921)
							(end 0.1016 0.1778)
						)
						(arc
							(start -0.1016 0.1778)
							(mid -0.137521 0.162921)
							(end -0.1524 0.127)
						)
						(arc
							(start -0.1524 -0.127)
							(mid -0.137521 -0.162921)
							(end -0.1016 -0.1778)
						)
						(arc
							(start 0.1016 -0.1778)
							(mid 0.137521 -0.162921)
							(end 0.1524 -0.127)
						)
					)
					(width 0)
					(fill yes)
				)
			)
		)
		(pad "2" smd custom
			(at 0 0.2794 270)
			(size 0.0762 0.0762)
			(layers "B.Cu" "B.Mask" "B.Paste")
			(net "GND")
			(options
				(clearance outline)
				(anchor circle)
			)
			(primitives
				(gr_poly
					(pts
						(arc
							(start 0.1524 0.127)
							(mid 0.137521 0.162921)
							(end 0.1016 0.1778)
						)
						(arc
							(start -0.1016 0.1778)
							(mid -0.137521 0.162921)
							(end -0.1524 0.127)
						)
						(arc
							(start -0.1524 -0.127)
							(mid -0.137521 -0.162921)
							(end -0.1016 -0.1778)
						)
						(arc
							(start 0.1016 -0.1778)
							(mid 0.137521 -0.162921)
							(end 0.1524 -0.127)
						)
					)
					(width 0)
					(fill yes)
				)
			)
		)
	)
	(footprint ""
		(layer "B.Cu")
		(at 243.1288 -41.995852 -90)
		(property "Reference" "C438"
			(at 0 0 90)
			(layer "B.SilkS")
			(hide yes)
			(effects
				(font
					(size 1.27 1.27)
				)
				(justify mirror)
			)
		)
		(property "Value" "SCD1U16V1KX-1-GP"
			(at 2.8321 -1.7399 270)
			(unlocked yes)
			(layer "B.Fab")
			(hide yes)
			(effects
				(font
					(size 1.016 1.016)
					(thickness 0.1524)
				)
				(justify mirror)
			)
		)
		(property "Device Type" "C0201H13"
			(at 2.8321 -3.2639 270)
			(unlocked yes)
			(layer "B.Fab")
			(hide yes)
			(effects
				(font
					(size 1.016 1.016)
					(thickness 0.1524)
				)
				(justify mirror)
			)
		)
		(duplicate_pad_numbers_are_jumpers no)
		(fp_rect
			(start 0.2794 0.6477)
			(end -0.2794 -0.6477)
			(stroke
				(width 0)
				(type default)
			)
			(fill no)
			(layer "B.CrtYd")
		)
		(fp_rect
			(start 0.2794 0.6477)
			(end -0.2794 -0.6477)
			(stroke
				(width 0)
				(type default)
			)
			(fill no)
			(layer "B.Fab")
		)
		(pad "1" smd custom
			(at 0 -0.2794 90)
			(size 0.0762 0.0762)
			(layers "B.Cu" "B.Mask" "B.Paste")
			(net "DUT_VDD")
			(options
				(clearance outline)
				(anchor circle)
			)
			(primitives
				(gr_poly
					(pts
						(arc
							(start 0.1524 0.127)
							(mid 0.137521 0.162921)
							(end 0.1016 0.1778)
						)
						(arc
							(start -0.1016 0.1778)
							(mid -0.137521 0.162921)
							(end -0.1524 0.127)
						)
						(arc
							(start -0.1524 -0.127)
							(mid -0.137521 -0.162921)
							(end -0.1016 -0.1778)
						)
						(arc
							(start 0.1016 -0.1778)
							(mid 0.137521 -0.162921)
							(end 0.1524 -0.127)
						)
					)
					(width 0)
					(fill yes)
				)
			)
		)
		(pad "2" smd custom
			(at 0 0.2794 90)
			(size 0.0762 0.0762)
			(layers "B.Cu" "B.Mask" "B.Paste")
			(net "GND")
			(options
				(clearance outline)
				(anchor circle)
			)
			(primitives
				(gr_poly
					(pts
						(arc
							(start 0.1524 0.127)
							(mid 0.137521 0.162921)
							(end 0.1016 0.1778)
						)
						(arc
							(start -0.1016 0.1778)
							(mid -0.137521 0.162921)
							(end -0.1524 0.127)
						)
						(arc
							(start -0.1524 -0.127)
							(mid -0.137521 -0.162921)
							(end -0.1016 -0.1778)
						)
						(arc
							(start 0.1016 -0.1778)
							(mid 0.137521 -0.162921)
							(end 0.1524 -0.127)
						)
					)
					(width 0)
					(fill yes)
				)
			)
		)
	)
	(footprint ""
		(layer "B.Cu")
		(at 252.603 -56.989472 -90)
		(property "Reference" "C607"
			(at 0 0 90)
			(layer "B.SilkS")
			(hide yes)
			(effects
				(font
					(size 1.27 1.27)
				)
				(justify mirror)
			)
		)
		(property "Value" "SCD1U16V1KX-1-GP"
			(at 2.8321 -1.7399 270)
			(unlocked yes)
			(layer "B.Fab")
			(hide yes)
			(effects
				(font
					(size 1.016 1.016)
					(thickness 0.1524)
				)
				(justify mirror)
			)
		)
		(property "Device Type" "C0201H13"
			(at 2.8321 -3.2639 270)
			(unlocked yes)
			(layer "B.Fab")
			(hide yes)
			(effects
				(font
					(size 1.016 1.016)
					(thickness 0.1524)
				)
				(justify mirror)
			)
		)
		(duplicate_pad_numbers_are_jumpers no)
		(fp_rect
			(start 0.2794 0.6477)
			(end -0.2794 -0.6477)
			(stroke
				(width 0)
				(type default)
			)
			(fill no)
			(layer "B.CrtYd")
		)
		(fp_rect
			(start 0.2794 0.6477)
			(end -0.2794 -0.6477)
			(stroke
				(width 0)
				(type default)
			)
			(fill no)
			(layer "B.Fab")
		)
		(pad "1" smd custom
			(at 0 -0.2794 90)
			(size 0.0762 0.0762)
			(layers "B.Cu" "B.Mask" "B.Paste")
			(net "DUT_AVD_PCIE")
			(options
				(clearance outline)
				(anchor circle)
			)
			(primitives
				(gr_poly
					(pts
						(arc
							(start 0.1524 0.127)
							(mid 0.137521 0.162921)
							(end 0.1016 0.1778)
						)
						(arc
							(start -0.1016 0.1778)
							(mid -0.137521 0.162921)
							(end -0.1524 0.127)
						)
						(arc
							(start -0.1524 -0.127)
							(mid -0.137521 -0.162921)
							(end -0.1016 -0.1778)
						)
						(arc
							(start 0.1016 -0.1778)
							(mid 0.137521 -0.162921)
							(end 0.1524 -0.127)
						)
					)
					(width 0)
					(fill yes)
				)
			)
		)
		(pad "2" smd custom
			(at 0 0.2794 90)
			(size 0.0762 0.0762)
			(layers "B.Cu" "B.Mask" "B.Paste")
			(net "GND")
			(options
				(clearance outline)
				(anchor circle)
			)
			(primitives
				(gr_poly
					(pts
						(arc
							(start 0.1524 0.127)
							(mid 0.137521 0.162921)
							(end 0.1016 0.1778)
						)
						(arc
							(start -0.1016 0.1778)
							(mid -0.137521 0.162921)
							(end -0.1524 0.127)
						)
						(arc
							(start -0.1524 -0.127)
							(mid -0.137521 -0.162921)
							(end -0.1016 -0.1778)
						)
						(arc
							(start 0.1016 -0.1778)
							(mid 0.137521 -0.162921)
							(end 0.1524 -0.127)
						)
					)
					(width 0)
					(fill yes)
				)
			)
		)
	)
	(footprint ""
		(layer "B.Cu")
		(at 243.967 -25.4 90)
		(property "Reference" "TP190"
			(at 0 0 90)
			(layer "B.SilkS")
			(hide yes)
			(effects
				(font
					(size 1.27 1.27)
				)
				(justify mirror)
			)
		)
		(property "Value" "TPAD28-2-GP"
			(at 0.0127 -1.6637 90)
			(unlocked yes)
			(layer "B.Fab")
			(hide yes)
			(effects
				(font
					(size 1.016 1.016)
					(thickness 0.1524)
				)
				(justify mirror)
			)
		)
		(property "Device Type" "TPAD28"
			(at 0.0127 -3.1877 90)
			(unlocked yes)
			(layer "B.Fab")
			(hide yes)
			(effects
				(font
					(size 1.016 1.016)
					(thickness 0.1524)
				)
				(justify mirror)
			)
		)
		(duplicate_pad_numbers_are_jumpers no)
		(fp_poly
			(pts
				(arc
					(start 0 0.3556)
					(mid 0 -0.3556)
					(end 0 0.3556)
				)
			)
			(stroke
				(width 0)
				(type default)
			)
			(fill no)
			(layer "B.CrtYd")
		)
		(fp_poly
			(pts
				(arc
					(start 0 0.6096)
					(mid 0 -0.6096)
					(end 0 0.6096)
				)
			)
			(stroke
				(width 0)
				(type default)
			)
			(fill no)
			(layer "B.Fab")
		)
		(pad "1" smd circle
			(at 0 0 270)
			(size 0.7112 0.7112)
			(layers "B.Cu" "B.Mask" "B.Paste")
			(net "LBI_OE#")
		)
	)
	(footprint ""
		(layer "B.Cu")
		(at 247.599962 -33.999932)
		(property "Reference" "TP299"
			(at 0 0 0)
			(layer "B.SilkS")
			(hide yes)
			(effects
				(font
					(size 1.27 1.27)
				)
				(justify mirror)
			)
		)
		(property "Value" "TPAD28-2-GP"
			(at 0.0127 -1.6637 0)
			(unlocked yes)
			(layer "B.Fab")
			(hide yes)
			(effects
				(font
					(size 1.016 1.016)
					(thickness 0.1524)
				)
				(justify mirror)
			)
		)
		(property "Device Type" "TPAD28"
			(at 0.0127 -3.1877 0)
			(unlocked yes)
			(layer "B.Fab")
			(hide yes)
			(effects
				(font
					(size 1.016 1.016)
					(thickness 0.1524)
				)
				(justify mirror)
			)
		)
		(duplicate_pad_numbers_are_jumpers no)
		(fp_poly
			(pts
				(arc
					(start 0.3556 0)
					(mid -0.3556 0)
					(end 0.3556 0)
				)
			)
			(stroke
				(width 0)
				(type default)
			)
			(fill no)
			(layer "B.CrtYd")
		)
		(fp_poly
			(pts
				(arc
					(start 0.6096 0)
					(mid -0.6096 0)
					(end 0.6096 0)
				)
			)
			(stroke
				(width 0)
				(type default)
			)
			(fill no)
			(layer "B.Fab")
		)
		(pad "1" smd circle
			(at 0 0 180)
			(size 0.7112 0.7112)
			(layers "B.Cu" "B.Mask" "B.Paste")
			(net "TWI_SDA9")
		)
	)
)
